# T6G (Grand Teton) — schematic netlist excerpt (pin names and nets, part order shuffled) for the footprints in the layout excerpt that follows; sources: Cadence DE-HDL packaged netlist, KiCad conversion of 04192023_DAF0TMB3IC0_F0TG_MB_C_brd_V02_OCP.brd

C571  Q_CAP  4.7UF 6.3V 20% X6S  pkg 0402  page 279 : A = P0V9_CPU0_RT0_2A ; B = GND
PR302  Q_RES  0 5% CHIP  pkg 0402LF  page 27 : A = SVID_PVDDCR_CPU0_P0_SVC_R ; B = SVID_PVDDCR_CPU0_P0_SVC

(kicad_pcb
	(version 20260206)
	(generator "pcbnew")
	(generator_version "10.0")
	(general
		(thickness 1.6)
		(legacy_teardrops no)
	)
	(paper "A4")
	(title_block
		(title "04192023_DAF0TMB3IC0_F0TG_MB_C_brd_V02_OCP.brd")
		(comment 1 "Grand Teton / footprints 7791-7792 of 8354")
	)
	(layers
		(0 "F.Cu" signal "TOP")
		(4 "In1.Cu" signal "GND")
		(6 "In2.Cu" signal "IN1")
		(8 "In3.Cu" signal "GND1")
		(10 "In4.Cu" signal "IN2")
		(12 "In5.Cu" signal "GND2")
		(14 "In6.Cu" signal "IN3")
		(16 "In7.Cu" signal "GND3")
		(18 "In8.Cu" signal "VCC")
		(20 "In9.Cu" signal "VCC1")
		(22 "In10.Cu" signal "GND4")
		(24 "In11.Cu" signal "IN4")
		(26 "In12.Cu" signal "GND5")
		(28 "In13.Cu" signal "IN5")
		(30 "In14.Cu" signal "GND6")
		(32 "In15.Cu" signal "IN6")
		(34 "In16.Cu" signal "GND7")
		(2 "B.Cu" signal "BOTTOM")
		(9 "F.Adhes" user "F.Adhesive")
		(11 "B.Adhes" user "B.Adhesive")
		(13 "F.Paste" user "Package Geometry/Pastemask Top")
		(15 "B.Paste" user "Package Geometry/Pastemask Bottom")
		(5 "F.SilkS" user "Ref Des/Silkscreen Top")
		(7 "B.SilkS" user "Ref Des/Silkscreen Bottom")
		(1 "F.Mask" user "Board Geometry/Soldermask Top")
		(3 "B.Mask" user "Board Geometry/Soldermask Bottom")
		(17 "Dwgs.User" user "User.Drawings")
		(19 "Cmts.User" user "User.Comments")
		(21 "Eco1.User" user "User.Eco1")
		(23 "Eco2.User" user "User.Eco2")
		(25 "Edge.Cuts" user "Board Geometry/Outline")
		(27 "Margin" user)
		(31 "F.CrtYd" user "Package Geometry/Place Bound Top")
		(29 "B.CrtYd" user "Package Geometry/Place Bound Bottom")
		(35 "F.Fab" user "Ref Des/Assembly Top")
		(33 "B.Fab" user "Ref Des/Assembly Bottom")
	)
	(footprint ""
		(layer "B.Cu")
		(at 320.19113 -398.942052 90)
		(property "Reference" "C571"
			(at 0 0 90)
			(layer "B.SilkS")
			(hide yes)
			(effects
				(font
					(size 1.27 1.27)
				)
				(justify mirror)
			)
		)
		(property "Value" ""
			(at 0 0 90)
			(layer "B.Fab")
			(effects
				(font
					(size 1.27 1.27)
				)
				(justify mirror)
			)
		)
		(duplicate_pad_numbers_are_jumpers no)
		(fp_line
			(start 0.7874 -0.4064)
			(end -0.7874 -0.4064)
			(stroke
				(width 0.1524)
				(type default)
			)
			(layer "B.SilkS")
		)
		(fp_line
			(start -0.7874 -0.4064)
			(end -0.7874 0.4064)
			(stroke
				(width 0.1524)
				(type default)
			)
			(layer "B.SilkS")
		)
		(fp_line
			(start 0.7874 0.4064)
			(end 0.7874 -0.4064)
			(stroke
				(width 0.1524)
				(type default)
			)
			(layer "B.SilkS")
		)
		(fp_line
			(start -0.7874 0.4064)
			(end 0.7874 0.4064)
			(stroke
				(width 0.1524)
				(type default)
			)
			(layer "B.SilkS")
		)
		(fp_line
			(start 0.67945 -0.305054)
			(end 0.12065 -0.305054)
			(stroke
				(width 0.1)
				(type default)
			)
			(layer "B.Fab")
		)
		(fp_line
			(start 0.12065 -0.305054)
			(end 0.12065 -0.2794)
			(stroke
				(width 0.1)
				(type default)
			)
			(layer "B.Fab")
		)
		(fp_line
			(start -0.12065 -0.3048)
			(end -0.67945 -0.3048)
			(stroke
				(width 0.1)
				(type default)
			)
			(layer "B.Fab")
		)
		(fp_line
			(start -0.67945 -0.3048)
			(end -0.67945 0.3048)
			(stroke
				(width 0.1)
				(type default)
			)
			(layer "B.Fab")
		)
		(fp_line
			(start 0.12065 -0.2794)
			(end -0.12065 -0.2794)
			(stroke
				(width 0.1)
				(type default)
			)
			(layer "B.Fab")
		)
		(fp_line
			(start -0.12065 -0.2794)
			(end -0.12065 -0.3048)
			(stroke
				(width 0.1)
				(type default)
			)
			(layer "B.Fab")
		)
		(fp_line
			(start 0.12065 0.2794)
			(end 0.12065 0.3048)
			(stroke
				(width 0.1)
				(type default)
			)
			(layer "B.Fab")
		)
		(fp_line
			(start -0.120396 0.2794)
			(end 0.12065 0.2794)
			(stroke
				(width 0.1)
				(type default)
			)
			(layer "B.Fab")
		)
		(fp_line
			(start 0.67945 0.3048)
			(end 0.67945 -0.305054)
			(stroke
				(width 0.1)
				(type default)
			)
			(layer "B.Fab")
		)
		(fp_line
			(start 0.12065 0.3048)
			(end 0.67945 0.3048)
			(stroke
				(width 0.1)
				(type default)
			)
			(layer "B.Fab")
		)
		(fp_line
			(start -0.120396 0.3048)
			(end -0.120396 0.2794)
			(stroke
				(width 0.1)
				(type default)
			)
			(layer "B.Fab")
		)
		(fp_line
			(start -0.67945 0.3048)
			(end -0.120396 0.3048)
			(stroke
				(width 0.1)
				(type default)
			)
			(layer "B.Fab")
		)
		(pad "1" smd circle
			(at 0.40005 0 270)
			(size 0 0)
			(layers "B.Cu" "B.Mask" "B.Paste")
			(net "P0V9_CPU0_RT0_2A")
		)
		(pad "2" smd circle
			(at -0.40005 0 270)
			(size 0 0)
			(layers "B.Cu" "B.Mask" "B.Paste")
			(net "GND")
		)
	)
	(footprint ""
		(layer "B.Cu")
		(at 367.102898 -215.303608 180)
		(property "Reference" "PR302"
			(at 0 0 0)
			(layer "B.SilkS")
			(hide yes)
			(effects
				(font
					(size 1.27 1.27)
				)
				(justify mirror)
			)
		)
		(property "Value" ""
			(at 0 0 0)
			(layer "B.Fab")
			(effects
				(font
					(size 1.27 1.27)
				)
				(justify mirror)
			)
		)
		(duplicate_pad_numbers_are_jumpers no)
		(fp_line
			(start 0.7874 0.4064)
			(end 0.7874 -0.4064)
			(stroke
				(width 0.1524)
				(type default)
			)
			(layer "B.SilkS")
		)
		(fp_line
			(start 0.7874 -0.4064)
			(end -0.7874 -0.4064)
			(stroke
				(width 0.1524)
				(type default)
			)
			(layer "B.SilkS")
		)
		(fp_line
			(start -0.7874 0.4064)
			(end 0.7874 0.4064)
			(stroke
				(width 0.1524)
				(type default)
			)
			(layer "B.SilkS")
		)
		(fp_line
			(start -0.7874 -0.4064)
			(end -0.7874 0.4064)
			(stroke
				(width 0.1524)
				(type default)
			)
			(layer "B.SilkS")
		)
		(fp_line
			(start 0.67945 0.3048)
			(end 0.67945 -0.305054)
			(stroke
				(width 0.1)
				(type default)
			)
			(layer "B.Fab")
		)
		(fp_line
			(start 0.67945 -0.305054)
			(end 0.12065 -0.305054)
			(stroke
				(width 0.1)
				(type default)
			)
			(layer "B.Fab")
		)
		(fp_line
			(start 0.12065 0.3048)
			(end 0.67945 0.3048)
			(stroke
				(width 0.1)
				(type default)
			)
			(layer "B.Fab")
		)
		(fp_line
			(start 0.12065 0.2794)
			(end 0.12065 0.3048)
			(stroke
				(width 0.1)
				(type default)
			)
			(layer "B.Fab")
		)
		(fp_line
			(start 0.12065 -0.2794)
			(end -0.12065 -0.2794)
			(stroke
				(width 0.1)
				(type default)
			)
			(layer "B.Fab")
		)
		(fp_line
			(start 0.12065 -0.305054)
			(end 0.12065 -0.2794)
			(stroke
				(width 0.1)
				(type default)
			)
			(layer "B.Fab")
		)
		(fp_line
			(start -0.120396 0.3048)
			(end -0.120396 0.2794)
			(stroke
				(width 0.1)
				(type default)
			)
			(layer "B.Fab")
		)
		(fp_line
			(start -0.120396 0.2794)
			(end 0.12065 0.2794)
			(stroke
				(width 0.1)
				(type default)
			)
			(layer "B.Fab")
		)
		(fp_line
			(start -0.12065 -0.2794)
			(end -0.12065 -0.3048)
			(stroke
				(width 0.1)
				(type default)
			)
			(layer "B.Fab")
		)
		(fp_line
			(start -0.12065 -0.3048)
			(end -0.67945 -0.3048)
			(stroke
				(width 0.1)
				(type default)
			)
			(layer "B.Fab")
		)
		(fp_line
			(start -0.67945 0.3048)
			(end -0.120396 0.3048)
			(stroke
				(width 0.1)
				(type default)
			)
			(layer "B.Fab")
		)
		(fp_line
			(start -0.67945 -0.3048)
			(end -0.67945 0.3048)
			(stroke
				(width 0.1)
				(type default)
			)
			(layer "B.Fab")
		)
		(pad "1" smd circle
			(at 0.40005 0)
			(size 0 0)
			(layers "B.Cu" "B.Mask" "B.Paste")
			(net "SVID_PVDDCR_CPU0_P0_SVC_R")
		)
		(pad "2" smd circle
			(at -0.40005 0)
			(size 0 0)
			(layers "B.Cu" "B.Mask" "B.Paste")
			(net "SVID_PVDDCR_CPU0_P0_SVC")
		)
	)
)
